(kicad_pcb
	(version 20260206)
	(generator "pcbnew")
	(generator_version "10.0")
	(general
		(thickness 1.6)
		(legacy_teardrops no)
	)
	(paper "A4")
	(title_block
		(title "baseboard — 13948-1b.1110WZS1818.brd")
		(comment 1 "Honey Badger (Wiwynn) / footprints 729-736 of 2523")
	)
	(layers
		(0 "F.Cu" signal "TOP")
		(4 "In1.Cu" signal "L2GND")
		(6 "In2.Cu" signal "L3")
		(8 "In3.Cu" signal "L4VCC")
		(10 "In4.Cu" signal "L5VCC")
		(12 "In5.Cu" signal "L6")
		(14 "In6.Cu" signal "L7GND")
		(2 "B.Cu" signal "BOTTOM")
		(9 "F.Adhes" user "F.Adhesive")
		(11 "B.Adhes" user "B.Adhesive")
		(13 "F.Paste" user "Package Geometry/Pastemask Top")
		(15 "B.Paste" user "Package Geometry/Pastemask Bottom")
		(5 "F.SilkS" user "Ref Des/Silkscreen Top")
		(7 "B.SilkS" user "Ref Des/Silkscreen Bottom")
		(1 "F.Mask" user "Board Geometry/Soldermask Top")
		(3 "B.Mask" user "Board Geometry/Soldermask Bottom")
		(17 "Dwgs.User" user "User.Drawings")
		(19 "Cmts.User" user "User.Comments")
		(21 "Eco1.User" user "User.Eco1")
		(23 "Eco2.User" user "User.Eco2")
		(25 "Edge.Cuts" user "Board Geometry/Outline")
		(27 "Margin" user)
		(31 "F.CrtYd" user "Package Geometry/Place Bound Top")
		(29 "B.CrtYd" user "Package Geometry/Place Bound Bottom")
		(35 "F.Fab" user "Ref Des/Assembly Top")
		(33 "B.Fab" user "Ref Des/Assembly Bottom")
	)
	(footprint ""
		(layer "F.Cu")
		(at 274.193 -161.417 90)
		(property "Reference" "R292"
			(at 0 0 90)
			(layer "F.SilkS")
			(hide yes)
			(effects
				(font
					(size 1.27 1.27)
				)
			)
		)
		(property "Value" "0R2J-2-GP"
			(at 0.064008 -3.993896 90)
			(unlocked yes)
			(layer "F.Fab")
			(hide yes)
			(effects
				(font
					(size 1.016 1.016)
					(thickness 0.1524)
				)
			)
		)
		(property "Device Type" "R402H16"
			(at 0.064008 -5.517896 90)
			(unlocked yes)
			(layer "F.Fab")
			(hide yes)
			(effects
				(font
					(size 1.016 1.016)
					(thickness 0.1524)
				)
			)
		)
		(duplicate_pad_numbers_are_jumpers no)
		(fp_line
			(start 0.508 -0.9398)
			(end -0.508 -0.9398)
			(stroke
				(width 0.1524)
				(type default)
			)
			(layer "F.SilkS")
		)
		(fp_line
			(start -0.508 -0.9398)
			(end -0.508 0.9398)
			(stroke
				(width 0.1524)
				(type default)
			)
			(layer "F.SilkS")
		)
		(fp_rect
			(start -0.508 0.9398)
			(end 0.508 -0.9398)
			(stroke
				(width 0)
				(type default)
			)
			(fill no)
			(layer "F.CrtYd")
		)
		(fp_rect
			(start -0.508 0.9398)
			(end 0.508 -0.9398)
			(stroke
				(width 0)
				(type default)
			)
			(fill no)
			(layer "F.Fab")
		)
		(pad "1" smd custom
			(at 0 -0.4445 90)
			(size 0.1397 0.1397)
			(layers "F.Cu" "F.Mask" "F.Paste")
			(net "BMC_EN_P3V3")
			(options
				(clearance outline)
				(anchor circle)
			)
			(primitives
				(gr_poly
					(pts
						(arc
							(start -0.1778 -0.2794)
							(mid -0.249642 -0.249642)
							(end -0.2794 -0.1778)
						)
						(arc
							(start -0.2794 0.1778)
							(mid -0.249642 0.249642)
							(end -0.1778 0.2794)
						)
						(arc
							(start 0.1778 0.2794)
							(mid 0.249642 0.249642)
							(end 0.2794 0.1778)
						)
						(arc
							(start 0.2794 -0.1778)
							(mid 0.249642 -0.249642)
							(end 0.1778 -0.2794)
						)
					)
					(width 0)
					(fill yes)
				)
			)
		)
		(pad "2" smd custom
			(at 0 0.4445 90)
			(size 0.1397 0.1397)
			(layers "F.Cu" "F.Mask" "F.Paste")
			(net "BMC_EN_P3V3_R")
			(options
				(clearance outline)
				(anchor circle)
			)
			(primitives
				(gr_poly
					(pts
						(arc
							(start -0.1778 -0.2794)
							(mid -0.249642 -0.249642)
							(end -0.2794 -0.1778)
						)
						(arc
							(start -0.2794 0.1778)
							(mid -0.249642 0.249642)
							(end -0.1778 0.2794)
						)
						(arc
							(start 0.1778 0.2794)
							(mid 0.249642 0.249642)
							(end 0.2794 0.1778)
						)
						(arc
							(start 0.2794 -0.1778)
							(mid 0.249642 -0.249642)
							(end 0.1778 -0.2794)
						)
					)
					(width 0)
					(fill yes)
				)
			)
		)
	)
	(footprint ""
		(layer "F.Cu")
		(at 268.224 -214.503 90)
		(property "Reference" "PC99"
			(at 0 0 90)
			(layer "F.SilkS")
			(hide yes)
			(effects
				(font
					(size 1.27 1.27)
				)
			)
		)
		(property "Value" "SCD1U10V2KX-5GP"
			(at 1.1811 -2.7051 90)
			(unlocked yes)
			(layer "F.Fab")
			(hide yes)
			(effects
				(font
					(size 1.016 1.016)
					(thickness 0.1524)
				)
			)
		)
		(property "Device Type" "C402H22"
			(at 1.1811 -4.2291 90)
			(unlocked yes)
			(layer "F.Fab")
			(hide yes)
			(effects
				(font
					(size 1.016 1.016)
					(thickness 0.1524)
				)
			)
		)
		(duplicate_pad_numbers_are_jumpers no)
		(fp_rect
			(start -0.4318 0.9525)
			(end 0.4318 -0.9525)
			(stroke
				(width 0)
				(type default)
			)
			(fill no)
			(layer "F.CrtYd")
		)
		(fp_rect
			(start -0.4318 0.9525)
			(end 0.4318 -0.9525)
			(stroke
				(width 0)
				(type default)
			)
			(fill no)
			(layer "F.Fab")
		)
		(pad "1" smd custom
			(at 0 -0.4445 90)
			(size 0.1524 0.1524)
			(layers "F.Cu" "F.Mask" "F.Paste")
			(net "TPS74801_1V26_STBY_OUT")
			(options
				(clearance outline)
				(anchor circle)
			)
			(primitives
				(gr_poly
					(pts
						(arc
							(start 0.3048 -0.2032)
							(mid 0.275042 -0.275042)
							(end 0.2032 -0.3048)
						)
						(arc
							(start -0.2032 -0.3048)
							(mid -0.275042 -0.275042)
							(end -0.3048 -0.2032)
						)
						(arc
							(start -0.3048 0.2032)
							(mid -0.275042 0.275042)
							(end -0.2032 0.3048)
						)
						(arc
							(start 0.2032 0.3048)
							(mid 0.275042 0.275042)
							(end 0.3048 0.2032)
						)
					)
					(width 0)
					(fill yes)
				)
			)
		)
		(pad "2" smd custom
			(at 0 0.4445 90)
			(size 0.1524 0.1524)
			(layers "F.Cu" "F.Mask" "F.Paste")
			(net "GND")
			(options
				(clearance outline)
				(anchor circle)
			)
			(primitives
				(gr_poly
					(pts
						(arc
							(start 0.3048 -0.2032)
							(mid 0.275042 -0.275042)
							(end 0.2032 -0.3048)
						)
						(arc
							(start -0.2032 -0.3048)
							(mid -0.275042 -0.275042)
							(end -0.3048 -0.2032)
						)
						(arc
							(start -0.3048 0.2032)
							(mid -0.275042 0.275042)
							(end -0.2032 0.3048)
						)
						(arc
							(start 0.2032 0.3048)
							(mid 0.275042 0.275042)
							(end 0.3048 0.2032)
						)
					)
					(width 0)
					(fill yes)
				)
			)
		)
	)
	(footprint ""
		(layer "F.Cu")
		(at 179.324 -17.272 90)
		(property "Reference" "R202"
			(at 0 0 90)
			(layer "F.SilkS")
			(hide yes)
			(effects
				(font
					(size 1.27 1.27)
				)
			)
		)
		(property "Value" "49D9R2D-GP"
			(at 0.064008 -3.993896 90)
			(unlocked yes)
			(layer "F.Fab")
			(hide yes)
			(effects
				(font
					(size 1.016 1.016)
					(thickness 0.1524)
				)
			)
		)
		(property "Device Type" "R402H16"
			(at 0.064008 -5.517896 90)
			(unlocked yes)
			(layer "F.Fab")
			(hide yes)
			(effects
				(font
					(size 1.016 1.016)
					(thickness 0.1524)
				)
			)
		)
		(duplicate_pad_numbers_are_jumpers no)
		(fp_line
			(start 0.508 -0.9398)
			(end -0.508 -0.9398)
			(stroke
				(width 0.1524)
				(type default)
			)
			(layer "F.SilkS")
		)
		(fp_line
			(start -0.508 -0.9398)
			(end -0.508 0.9398)
			(stroke
				(width 0.1524)
				(type default)
			)
			(layer "F.SilkS")
		)
		(fp_rect
			(start -0.508 0.9398)
			(end 0.508 -0.9398)
			(stroke
				(width 0)
				(type default)
			)
			(fill no)
			(layer "F.CrtYd")
		)
		(fp_rect
			(start -0.508 0.9398)
			(end 0.508 -0.9398)
			(stroke
				(width 0)
				(type default)
			)
			(fill no)
			(layer "F.Fab")
		)
		(pad "1" smd custom
			(at 0 -0.4445 90)
			(size 0.1397 0.1397)
			(layers "F.Cu" "F.Mask" "F.Paste")
			(net "TEMP_SENSOR_DXN_BJT")
			(options
				(clearance outline)
				(anchor circle)
			)
			(primitives
				(gr_poly
					(pts
						(arc
							(start -0.1778 -0.2794)
							(mid -0.249642 -0.249642)
							(end -0.2794 -0.1778)
						)
						(arc
							(start -0.2794 0.1778)
							(mid -0.249642 0.249642)
							(end -0.1778 0.2794)
						)
						(arc
							(start 0.1778 0.2794)
							(mid 0.249642 0.249642)
							(end 0.2794 0.1778)
						)
						(arc
							(start 0.2794 -0.1778)
							(mid 0.249642 -0.249642)
							(end 0.1778 -0.2794)
						)
					)
					(width 0)
					(fill yes)
				)
			)
		)
		(pad "2" smd custom
			(at 0 0.4445 90)
			(size 0.1397 0.1397)
			(layers "F.Cu" "F.Mask" "F.Paste")
			(net "TEMP_SENSOR_DXN")
			(options
				(clearance outline)
				(anchor circle)
			)
			(primitives
				(gr_poly
					(pts
						(arc
							(start -0.1778 -0.2794)
							(mid -0.249642 -0.249642)
							(end -0.2794 -0.1778)
						)
						(arc
							(start -0.2794 0.1778)
							(mid -0.249642 0.249642)
							(end -0.1778 0.2794)
						)
						(arc
							(start 0.1778 0.2794)
							(mid 0.249642 0.249642)
							(end 0.2794 0.1778)
						)
						(arc
							(start 0.2794 -0.1778)
							(mid 0.249642 -0.249642)
							(end 0.1778 -0.2794)
						)
					)
					(width 0)
					(fill yes)
				)
			)
		)
	)
	(footprint ""
		(layer "F.Cu")
		(at 344.424 -113.792 90)
		(property "Reference" "PR11"
			(at 0 0 90)
			(layer "F.SilkS")
			(hide yes)
			(effects
				(font
					(size 1.27 1.27)
				)
			)
		)
		(property "Value" "0R2J-2-GP"
			(at 0.064008 -3.993896 90)
			(unlocked yes)
			(layer "F.Fab")
			(hide yes)
			(effects
				(font
					(size 1.016 1.016)
					(thickness 0.1524)
				)
			)
		)
		(property "Device Type" "R402H16"
			(at 0.064008 -5.517896 90)
			(unlocked yes)
			(layer "F.Fab")
			(hide yes)
			(effects
				(font
					(size 1.016 1.016)
					(thickness 0.1524)
				)
			)
		)
		(duplicate_pad_numbers_are_jumpers no)
		(fp_line
			(start 0.508 -0.9398)
			(end -0.508 -0.9398)
			(stroke
				(width 0.1524)
				(type default)
			)
			(layer "F.SilkS")
		)
		(fp_line
			(start -0.508 -0.9398)
			(end -0.508 0.9398)
			(stroke
				(width 0.1524)
				(type default)
			)
			(layer "F.SilkS")
		)
		(fp_rect
			(start -0.508 0.9398)
			(end 0.508 -0.9398)
			(stroke
				(width 0)
				(type default)
			)
			(fill no)
			(layer "F.CrtYd")
		)
		(fp_rect
			(start -0.508 0.9398)
			(end 0.508 -0.9398)
			(stroke
				(width 0)
				(type default)
			)
			(fill no)
			(layer "F.Fab")
		)
		(pad "1" smd custom
			(at 0 -0.4445 90)
			(size 0.1397 0.1397)
			(layers "F.Cu" "F.Mask" "F.Paste")
			(net "P5V_STBY_VO")
			(options
				(clearance outline)
				(anchor circle)
			)
			(primitives
				(gr_poly
					(pts
						(arc
							(start -0.1778 -0.2794)
							(mid -0.249642 -0.249642)
							(end -0.2794 -0.1778)
						)
						(arc
							(start -0.2794 0.1778)
							(mid -0.249642 0.249642)
							(end -0.1778 0.2794)
						)
						(arc
							(start 0.1778 0.2794)
							(mid 0.249642 0.249642)
							(end 0.2794 0.1778)
						)
						(arc
							(start 0.2794 -0.1778)
							(mid 0.249642 -0.249642)
							(end 0.1778 -0.2794)
						)
					)
					(width 0)
					(fill yes)
				)
			)
		)
		(pad "2" smd custom
			(at 0 0.4445 90)
			(size 0.1397 0.1397)
			(layers "F.Cu" "F.Mask" "F.Paste")
			(net "P5V_STBY_CC_R")
			(options
				(clearance outline)
				(anchor circle)
			)
			(primitives
				(gr_poly
					(pts
						(arc
							(start -0.1778 -0.2794)
							(mid -0.249642 -0.249642)
							(end -0.2794 -0.1778)
						)
						(arc
							(start -0.2794 0.1778)
							(mid -0.249642 0.249642)
							(end -0.1778 0.2794)
						)
						(arc
							(start 0.1778 0.2794)
							(mid 0.249642 0.249642)
							(end 0.2794 0.1778)
						)
						(arc
							(start 0.2794 -0.1778)
							(mid 0.249642 -0.249642)
							(end 0.1778 -0.2794)
						)
					)
					(width 0)
					(fill yes)
				)
			)
		)
	)
	(footprint ""
		(layer "F.Cu")
		(at 97.795842 -98.496882)
		(property "Reference" "STP96"
			(at 0 0 0)
			(layer "F.SilkS")
			(hide yes)
			(effects
				(font
					(size 1.27 1.27)
				)
			)
		)
		(property "Value" "TPAD28"
			(at 0.0127 -1.8034 0)
			(unlocked yes)
			(layer "F.Fab")
			(hide yes)
			(effects
				(font
					(size 1.016 1.016)
					(thickness 0.1524)
				)
			)
		)
		(property "Device Type" "TPAD28"
			(at 0.0127 -3.3274 0)
			(unlocked yes)
			(layer "F.Fab")
			(hide yes)
			(effects
				(font
					(size 1.016 1.016)
					(thickness 0.1524)
				)
			)
		)
		(duplicate_pad_numbers_are_jumpers no)
		(fp_poly
			(pts
				(arc
					(start 0.3556 0)
					(mid -0.3556 0)
					(end 0.3556 0)
				)
			)
			(stroke
				(width 0)
				(type default)
			)
			(fill no)
			(layer "F.CrtYd")
		)
		(fp_poly
			(pts
				(arc
					(start 0.6096 0)
					(mid -0.6096 0)
					(end 0.6096 0)
				)
			)
			(stroke
				(width 0)
				(type default)
			)
			(fill no)
			(layer "F.Fab")
		)
		(pad "1" smd circle
			(at 0 0)
			(size 0.7112 0.7112)
			(layers "F.Cu" "F.Mask" "F.Paste")
			(net "LSI_EFUSE")
		)
	)
	(footprint ""
		(layer "F.Cu")
		(at 283.845 -156.464)
		(property "Reference" "R20"
			(at 0 0 0)
			(layer "F.SilkS")
			(hide yes)
			(effects
				(font
					(size 1.27 1.27)
				)
			)
		)
		(property "Value" "100R2F-L1-GP-U"
			(at 0.064008 -3.993896 0)
			(unlocked yes)
			(layer "F.Fab")
			(hide yes)
			(effects
				(font
					(size 1.016 1.016)
					(thickness 0.1524)
				)
			)
		)
		(property "Device Type" "R402H14"
			(at 0.064008 -5.517896 0)
			(unlocked yes)
			(layer "F.Fab")
			(hide yes)
			(effects
				(font
					(size 1.016 1.016)
					(thickness 0.1524)
				)
			)
		)
		(duplicate_pad_numbers_are_jumpers no)
		(fp_line
			(start -0.508 -0.9398)
			(end -0.508 0.9398)
			(stroke
				(width 0.1524)
				(type default)
			)
			(layer "F.SilkS")
		)
		(fp_line
			(start 0.508 -0.9398)
			(end -0.508 -0.9398)
			(stroke
				(width 0.1524)
				(type default)
			)
			(layer "F.SilkS")
		)
		(fp_rect
			(start -0.508 0.9398)
			(end 0.508 -0.9398)
			(stroke
				(width 0)
				(type default)
			)
			(fill no)
			(layer "F.CrtYd")
		)
		(fp_rect
			(start -0.508 0.9398)
			(end 0.508 -0.9398)
			(stroke
				(width 0)
				(type default)
			)
			(fill no)
			(layer "F.Fab")
		)
		(pad "1" smd custom
			(at 0 -0.4445)
			(size 0.1397 0.1397)
			(layers "F.Cu" "F.Mask" "F.Paste")
			(net "BMC_LSI_BOARD")
			(options
				(clearance outline)
				(anchor circle)
			)
			(primitives
				(gr_poly
					(pts
						(arc
							(start -0.1778 -0.2794)
							(mid -0.249642 -0.249642)
							(end -0.2794 -0.1778)
						)
						(arc
							(start -0.2794 0.1778)
							(mid -0.249642 0.249642)
							(end -0.1778 0.2794)
						)
						(arc
							(start 0.1778 0.2794)
							(mid 0.249642 0.249642)
							(end 0.2794 0.1778)
						)
						(arc
							(start 0.2794 -0.1778)
							(mid 0.249642 -0.249642)
							(end 0.1778 -0.2794)
						)
					)
					(width 0)
					(fill yes)
				)
			)
		)
		(pad "2" smd custom
			(at 0 0.4445)
			(size 0.1397 0.1397)
			(layers "F.Cu" "F.Mask" "F.Paste")
			(net "GND")
			(options
				(clearance outline)
				(anchor circle)
			)
			(primitives
				(gr_poly
					(pts
						(arc
							(start -0.1778 -0.2794)
							(mid -0.249642 -0.249642)
							(end -0.2794 -0.1778)
						)
						(arc
							(start -0.2794 0.1778)
							(mid -0.249642 0.249642)
							(end -0.1778 0.2794)
						)
						(arc
							(start 0.1778 0.2794)
							(mid 0.249642 0.249642)
							(end 0.2794 0.1778)
						)
						(arc
							(start 0.2794 -0.1778)
							(mid 0.249642 -0.249642)
							(end 0.1778 -0.2794)
						)
					)
					(width 0)
					(fill yes)
				)
			)
		)
	)
	(footprint ""
		(layer "F.Cu")
		(at 97.54997 -94.234)
		(property "Reference" "STP99"
			(at 0 0 0)
			(layer "F.SilkS")
			(hide yes)
			(effects
				(font
					(size 1.27 1.27)
				)
			)
		)
		(property "Value" "TPAD28"
			(at 0.0127 -1.8034 0)
			(unlocked yes)
			(layer "F.Fab")
			(hide yes)
			(effects
				(font
					(size 1.016 1.016)
					(thickness 0.1524)
				)
			)
		)
		(property "Device Type" "TPAD28"
			(at 0.0127 -3.3274 0)
			(unlocked yes)
			(layer "F.Fab")
			(hide yes)
			(effects
				(font
					(size 1.016 1.016)
					(thickness 0.1524)
				)
			)
		)
		(duplicate_pad_numbers_are_jumpers no)
		(fp_poly
			(pts
				(arc
					(start 0.3556 0)
					(mid -0.3556 0)
					(end 0.3556 0)
				)
			)
			(stroke
				(width 0)
				(type default)
			)
			(fill no)
			(layer "F.CrtYd")
		)
		(fp_poly
			(pts
				(arc
					(start 0.6096 0)
					(mid -0.6096 0)
					(end 0.6096 0)
				)
			)
			(stroke
				(width 0)
				(type default)
			)
			(fill no)
			(layer "F.Fab")
		)
		(pad "1" smd circle
			(at 0 0)
			(size 0.7112 0.7112)
			(layers "F.Cu" "F.Mask" "F.Paste")
			(net "LSI_SCAN_ENABLE")
		)
	)
	(footprint ""
		(layer "F.Cu")
		(at 69.469 -50.673)
		(property "Reference" "SR714"
			(at 0 0 0)
			(layer "F.SilkS")
			(hide yes)
			(effects
				(font
					(size 1.27 1.27)
				)
			)
		)
		(property "Value" "10R2F-L-GP"
			(at 0.064008 -3.993896 0)
			(unlocked yes)
			(layer "F.Fab")
			(hide yes)
			(effects
				(font
					(size 1.016 1.016)
					(thickness 0.1524)
				)
			)
		)
		(property "Device Type" "R402H14"
			(at 0.064008 -5.517896 0)
			(unlocked yes)
			(layer "F.Fab")
			(hide yes)
			(effects
				(font
					(size 1.016 1.016)
					(thickness 0.1524)
				)
			)
		)
		(duplicate_pad_numbers_are_jumpers no)
		(fp_line
			(start -0.508 -0.9398)
			(end -0.508 0.9398)
			(stroke
				(width 0.1524)
				(type default)
			)
			(layer "F.SilkS")
		)
		(fp_line
			(start 0.508 -0.9398)
			(end -0.508 -0.9398)
			(stroke
				(width 0.1524)
				(type default)
			)
			(layer "F.SilkS")
		)
		(fp_rect
			(start -0.508 0.9398)
			(end 0.508 -0.9398)
			(stroke
				(width 0)
				(type default)
			)
			(fill no)
			(layer "F.CrtYd")
		)
		(fp_rect
			(start -0.508 0.9398)
			(end 0.508 -0.9398)
			(stroke
				(width 0)
				(type default)
			)
			(fill no)
			(layer "F.Fab")
		)
		(pad "1" smd custom
			(at 0 -0.4445)
			(size 0.1397 0.1397)
			(layers "F.Cu" "F.Mask" "F.Paste")
			(net "P1V8_C")
			(options
				(clearance outline)
				(anchor circle)
			)
			(primitives
				(gr_poly
					(pts
						(arc
							(start -0.1778 -0.2794)
							(mid -0.249642 -0.249642)
							(end -0.2794 -0.1778)
						)
						(arc
							(start -0.2794 0.1778)
							(mid -0.249642 0.249642)
							(end -0.1778 0.2794)
						)
						(arc
							(start 0.1778 0.2794)
							(mid 0.249642 0.249642)
							(end 0.2794 0.1778)
						)
						(arc
							(start 0.2794 -0.1778)
							(mid 0.249642 -0.249642)
							(end 0.1778 -0.2794)
						)
					)
					(width 0)
					(fill yes)
				)
			)
		)
		(pad "2" smd custom
			(at 0 0.4445)
			(size 0.1397 0.1397)
			(layers "F.Cu" "F.Mask" "F.Paste")
			(net "SAS0_VDDH")
			(options
				(clearance outline)
				(anchor circle)
			)
			(primitives
				(gr_poly
					(pts
						(arc
							(start -0.1778 -0.2794)
							(mid -0.249642 -0.249642)
							(end -0.2794 -0.1778)
						)
						(arc
							(start -0.2794 0.1778)
							(mid -0.249642 0.249642)
							(end -0.1778 0.2794)
						)
						(arc
							(start 0.1778 0.2794)
							(mid 0.249642 0.249642)
							(end 0.2794 0.1778)
						)
						(arc
							(start 0.2794 -0.1778)
							(mid 0.249642 -0.249642)
							(end 0.1778 -0.2794)
						)
					)
					(width 0)
					(fill yes)
				)
			)
		)
	)
)
